# BARRELEYE_G2-FPDB_POST-PVT-X02-BOM-X05-20171123_Final.xls.xlsx — POP_GA (bom)
| FOXCONN TECHNOLOGY GROUP |  |  |  |  |  |  |  |  |  |  |  |  |
| BILL OF MATERIAL |  |  |  |  |  |  |  |  |  |  |  |  |
| REV OF  BOM |  | CUSTOMER | <name> |  | CUSTOMER P/N |  | PRODUCT CODE |  | PWA  REV |  | DATE |  |
| Sourcing (Single/Sole/Multi) | Critical Commodity (Y or N) | Component Class (1, 2, other) | Customer PSL (Y or N) | Item Number | Foxconn P/N | Customer P/N | Part Description | Manufacturer  Full Name | Manufacturer  Part Number | Qty | RoHS Status | Location |
